FILE_TYPE = MACRO_DRAWING;
SET COLOR_WIRE YELLOW;
SET COLOR_PROP ORANGE;
SET COLOR_DOT WHITE;
SET COLOR_ARC YELLOW;
SET COLOR_BODY GREEN;
SET COLOR_NOTE PURPLE;
SET PROP_DISPLAY VALUE;
SET PAGE_NUMBER P4;
SET PATH_NUMBER P0;
FORCEADD QUANTA_TITLE_BLOCK_C..1
(2800 -1000);
FORCEPROP 0 LAST CDS_CON_LAST_MODIFIED Fri Aug 25 17:25:34 2023
J 0
(915 -985);
DISPLAY INVISIBLE (915 -985);
FORCEPROP 2 LAST Q_DEPT 
J 1
(-963 -951);
DISPLAY 1.957447 (-963 -951);
PAINT GREEN (-963 -951);
FORCEPROP 1 LAST CUSTOM_TXT_CDS <CON_LAST_MODIFIED>
J 0
(915 -985);
DISPLAY 0.978723 (915 -985);
FORCEPROP 2 LAST CUSTOM_TXT_CDS <XR_PAGE_TITLE>
J 0
(-5090 4250);
DISPLAY 0.638298 (-5090 4250);
PAINT PINK (-5090 4250);
DISPLAY INVISIBLE (-5090 4250);
FORCEPROP 1 LAST CUSTOM_TXT_CDS <NAME_2>
J 0
(-375 -950);
FORCEPROP 1 LAST CUSTOM_TXT_CDS <NAME_1>
J 0
(-375 -825);
FORCEPROP 1 LAST CUSTOM_TXT_CDS <Q_NUMBER>
J 0
(1397 -897);
DISPLAY 1.212766 (1397 -897);
FORCEPROP 1 LAST CUSTOM_TXT_CDS <Q_PROJ>
J 0
(418 -898);
DISPLAY 1.212766 (418 -898);
FORCEPROP 1 LAST CUSTOM_TXT_CDS <Q_REV>
J 0
(2616 -897);
DISPLAY 1.212766 (2616 -897);
FORCEPROP 1 LAST CUSTOM_TXT_CDS <CON_PAGE_NUM> OF <CON_TOTAL_PAGES>
J 0
(2354 -982);
DISPLAY 0.978723 (2354 -982);
FORCEPROP 1 LAST Q_TITLE SPI DIAGRAM
J 0
(-6566 -974);
DISPLAY 2.446809 (-6566 -974);
PAINT GREEN (-6566 -974);
FORCEPROP 2 LAST PAGE_BORDER TRUE
J 0
(-5090 4250);
DISPLAY 0.638298 (-5090 4250);
PAINT PINK (-5090 4250);
DISPLAY INVISIBLE (-5090 4250);
FORCEPROP 1 LAST CDS_LMAN_SYM_OUTLINE -9475,6775,100,-125
J 0
(2800 -1000);
DISPLAY 0.468085 (2800 -1000);
PAINT GREEN (2800 -1000);
DISPLAY INVISIBLE (2800 -1000);
FORCEPROP 2 LAST CDS_LIB pure_quanta
J 0
(2800 -1000);
DISPLAY INVISIBLE (2800 -1000);
FORCEPROP 1 LAST COMMENT_BODY TRUE
J 0
(2812 -1013);
DISPLAY 0.978723 (2812 -1013);
PAINT PEACH (2812 -1013);
DISPLAY INVISIBLE (2812 -1013);
FORCEPROP 2 LAST CDS_XR_PAGE_TITLE CR-4 : @SCM_LIB.SCM(SCH_1):PAGE4
J 0
(-5090 4250);
DISPLAY 0.638298 (-5090 4250);
PAINT PINK (-5090 4250);
DISPLAY INVISIBLE (-5090 4250);
FORCENOTE
$CDS_IMAGE|GT_diagram_MB_20211123_1050_SPI.jpg|7885|6263
(-1875 2475) 0;
DISPLAY LEFT (-1875 2475);
QUIT
